# S9S_MB_2U (Grand Teton) — schematic netlist excerpt (pin names and nets, part order shuffled) for the footprints in the layout excerpt that follows; sources: Cadence DE-HDL packaged netlist, KiCad conversion of 03242023_DA0F0TMBIJ0_F0T_Motherboard_J_brd_V01_OCP.brd

C256  Q_CAP  10UF 6.3V 20% X6S  pkg C0402  page 77 : A = PVCCIN_CPU1 ; B = GND
R2350  Q_RES  0 5% CHIP  pkg 0402LF  page 191 : A = FM_PS_EN_PLD_BUF1 ; B = FM_PS_EN_PLD_BUF1_R1

(kicad_pcb
	(version 20260206)
	(generator "pcbnew")
	(generator_version "10.0")
	(general
		(thickness 1.6)
		(legacy_teardrops no)
	)
	(paper "A4")
	(title_block
		(title "03242023_DA0F0TMBIJ0_F0T_Motherboard_J_brd_V01_OCP.brd")
		(comment 1 "Grand Teton / footprints 2315-2316 of 6105")
	)
	(layers
		(0 "F.Cu" signal "TOP")
		(4 "In1.Cu" signal "GND")
		(6 "In2.Cu" signal "IN1")
		(8 "In3.Cu" signal "GND1")
		(10 "In4.Cu" signal "IN2")
		(12 "In5.Cu" signal "GND2")
		(14 "In6.Cu" signal "IN3")
		(16 "In7.Cu" signal "GND3")
		(18 "In8.Cu" signal "VCC")
		(20 "In9.Cu" signal "VCC1")
		(22 "In10.Cu" signal "GND4")
		(24 "In11.Cu" signal "IN4")
		(26 "In12.Cu" signal "GND5")
		(28 "In13.Cu" signal "IN5")
		(30 "In14.Cu" signal "GND6")
		(32 "In15.Cu" signal "IN6")
		(34 "In16.Cu" signal "GND7")
		(2 "B.Cu" signal "BOTTOM")
		(9 "F.Adhes" user "F.Adhesive")
		(11 "B.Adhes" user "B.Adhesive")
		(13 "F.Paste" user "Package Geometry/Pastemask Top")
		(15 "B.Paste" user "Package Geometry/Pastemask Bottom")
		(5 "F.SilkS" user "Ref Des/Silkscreen Top")
		(7 "B.SilkS" user "Ref Des/Silkscreen Bottom")
		(1 "F.Mask" user "Board Geometry/Soldermask Top")
		(3 "B.Mask" user "Board Geometry/Soldermask Bottom")
		(17 "Dwgs.User" user "User.Drawings")
		(19 "Cmts.User" user "User.Comments")
		(21 "Eco1.User" user "User.Eco1")
		(23 "Eco2.User" user "User.Eco2")
		(25 "Edge.Cuts" user "Board Geometry/Outline")
		(27 "Margin" user)
		(31 "F.CrtYd" user "Package Geometry/Place Bound Top")
		(29 "B.CrtYd" user "Package Geometry/Place Bound Bottom")
		(35 "F.Fab" user "Ref Des/Assembly Top")
		(33 "B.Fab" user "Ref Des/Assembly Bottom")
	)
	(footprint ""
		(layer "F.Cu")
		(at 104.3432 -251.375672 90)
		(property "Reference" "C256"
			(at 0 0 90)
			(layer "F.SilkS")
			(hide yes)
			(effects
				(font
					(size 1.27 1.27)
				)
			)
		)
		(property "Value" ""
			(at 0 0 90)
			(layer "F.Fab")
			(effects
				(font
					(size 1.27 1.27)
				)
			)
		)
		(duplicate_pad_numbers_are_jumpers no)
		(fp_line
			(start 0.7874 -0.4064)
			(end 0.7874 0.4064)
			(stroke
				(width 0.1524)
				(type default)
			)
			(layer "F.SilkS")
		)
		(fp_line
			(start -0.7874 -0.4064)
			(end 0.7874 -0.4064)
			(stroke
				(width 0.1524)
				(type default)
			)
			(layer "F.SilkS")
		)
		(fp_line
			(start 0.7874 0.4064)
			(end -0.7874 0.4064)
			(stroke
				(width 0.1524)
				(type default)
			)
			(layer "F.SilkS")
		)
		(fp_line
			(start -0.7874 0.4064)
			(end -0.7874 -0.4064)
			(stroke
				(width 0.1524)
				(type default)
			)
			(layer "F.SilkS")
		)
		(fp_line
			(start -0.12065 -0.305054)
			(end -0.12065 -0.2794)
			(stroke
				(width 0.1)
				(type default)
			)
			(layer "F.Fab")
		)
		(fp_line
			(start -0.67945 -0.305054)
			(end -0.12065 -0.305054)
			(stroke
				(width 0.1)
				(type default)
			)
			(layer "F.Fab")
		)
		(fp_line
			(start 0.67945 -0.3048)
			(end 0.67945 0.3048)
			(stroke
				(width 0.1)
				(type default)
			)
			(layer "F.Fab")
		)
		(fp_line
			(start 0.12065 -0.3048)
			(end 0.67945 -0.3048)
			(stroke
				(width 0.1)
				(type default)
			)
			(layer "F.Fab")
		)
		(fp_line
			(start 0.12065 -0.2794)
			(end 0.12065 -0.3048)
			(stroke
				(width 0.1)
				(type default)
			)
			(layer "F.Fab")
		)
		(fp_line
			(start -0.12065 -0.2794)
			(end 0.12065 -0.2794)
			(stroke
				(width 0.1)
				(type default)
			)
			(layer "F.Fab")
		)
		(fp_line
			(start 0.120396 0.2794)
			(end -0.12065 0.2794)
			(stroke
				(width 0.1)
				(type default)
			)
			(layer "F.Fab")
		)
		(fp_line
			(start -0.12065 0.2794)
			(end -0.12065 0.3048)
			(stroke
				(width 0.1)
				(type default)
			)
			(layer "F.Fab")
		)
		(fp_line
			(start 0.67945 0.3048)
			(end 0.120396 0.3048)
			(stroke
				(width 0.1)
				(type default)
			)
			(layer "F.Fab")
		)
		(fp_line
			(start 0.120396 0.3048)
			(end 0.120396 0.2794)
			(stroke
				(width 0.1)
				(type default)
			)
			(layer "F.Fab")
		)
		(fp_line
			(start -0.12065 0.3048)
			(end -0.67945 0.3048)
			(stroke
				(width 0.1)
				(type default)
			)
			(layer "F.Fab")
		)
		(fp_line
			(start -0.67945 0.3048)
			(end -0.67945 -0.305054)
			(stroke
				(width 0.1)
				(type default)
			)
			(layer "F.Fab")
		)
		(pad "1" smd circle
			(at -0.40005 0 90)
			(size 0 0)
			(layers "F.Cu" "F.Mask" "F.Paste")
			(net "PVCCIN_CPU1")
		)
		(pad "2" smd circle
			(at 0.40005 0 90)
			(size 0 0)
			(layers "F.Cu" "F.Mask" "F.Paste")
			(net "GND")
		)
	)
	(footprint ""
		(layer "F.Cu")
		(at 141.240256 -65.329308)
		(property "Reference" "R2350"
			(at 0 0 0)
			(layer "F.SilkS")
			(hide yes)
			(effects
				(font
					(size 1.27 1.27)
				)
			)
		)
		(property "Value" ""
			(at 0 0 0)
			(layer "F.Fab")
			(effects
				(font
					(size 1.27 1.27)
				)
			)
		)
		(duplicate_pad_numbers_are_jumpers no)
		(fp_line
			(start -0.7874 -0.4064)
			(end 0.7874 -0.4064)
			(stroke
				(width 0.1524)
				(type default)
			)
			(layer "F.SilkS")
		)
		(fp_line
			(start -0.7874 0.4064)
			(end -0.7874 -0.4064)
			(stroke
				(width 0.1524)
				(type default)
			)
			(layer "F.SilkS")
		)
		(fp_line
			(start 0.7874 -0.4064)
			(end 0.7874 0.4064)
			(stroke
				(width 0.1524)
				(type default)
			)
			(layer "F.SilkS")
		)
		(fp_line
			(start 0.7874 0.4064)
			(end -0.7874 0.4064)
			(stroke
				(width 0.1524)
				(type default)
			)
			(layer "F.SilkS")
		)
		(fp_line
			(start -0.67945 -0.305054)
			(end -0.12065 -0.305054)
			(stroke
				(width 0.1)
				(type default)
			)
			(layer "F.Fab")
		)
		(fp_line
			(start -0.67945 0.3048)
			(end -0.67945 -0.305054)
			(stroke
				(width 0.1)
				(type default)
			)
			(layer "F.Fab")
		)
		(fp_line
			(start -0.12065 -0.305054)
			(end -0.12065 -0.2794)
			(stroke
				(width 0.1)
				(type default)
			)
			(layer "F.Fab")
		)
		(fp_line
			(start -0.12065 -0.2794)
			(end 0.12065 -0.2794)
			(stroke
				(width 0.1)
				(type default)
			)
			(layer "F.Fab")
		)
		(fp_line
			(start -0.12065 0.2794)
			(end -0.12065 0.3048)
			(stroke
				(width 0.1)
				(type default)
			)
			(layer "F.Fab")
		)
		(fp_line
			(start -0.12065 0.3048)
			(end -0.67945 0.3048)
			(stroke
				(width 0.1)
				(type default)
			)
			(layer "F.Fab")
		)
		(fp_line
			(start 0.120396 0.2794)
			(end -0.12065 0.2794)
			(stroke
				(width 0.1)
				(type default)
			)
			(layer "F.Fab")
		)
		(fp_line
			(start 0.120396 0.3048)
			(end 0.120396 0.2794)
			(stroke
				(width 0.1)
				(type default)
			)
			(layer "F.Fab")
		)
		(fp_line
			(start 0.12065 -0.3048)
			(end 0.67945 -0.3048)
			(stroke
				(width 0.1)
				(type default)
			)
			(layer "F.Fab")
		)
		(fp_line
			(start 0.12065 -0.2794)
			(end 0.12065 -0.3048)
			(stroke
				(width 0.1)
				(type default)
			)
			(layer "F.Fab")
		)
		(fp_line
			(start 0.67945 -0.3048)
			(end 0.67945 0.3048)
			(stroke
				(width 0.1)
				(type default)
			)
			(layer "F.Fab")
		)
		(fp_line
			(start 0.67945 0.3048)
			(end 0.120396 0.3048)
			(stroke
				(width 0.1)
				(type default)
			)
			(layer "F.Fab")
		)
		(pad "1" smd circle
			(at -0.40005 0)
			(size 0 0)
			(layers "F.Cu" "F.Mask" "F.Paste")
			(net "FM_PS_EN_PLD_BUF1")
		)
		(pad "2" smd circle
			(at 0.40005 0)
			(size 0 0)
			(layers "F.Cu" "F.Mask" "F.Paste")
			(net "FM_PS_EN_PLD_BUF1_R1")
		)
	)
)
